(kicad_pcb
	(version 20260206)
	(generator "pcbnew")
	(generator_version "10.0")
	(general
		(thickness 1.6)
		(legacy_teardrops no)
	)
	(paper "A4")
	(title_block
		(title "netronome-mezz — pcbd0082-001_rev01_jul9_a.brd")
		(comment 1 "Open CloudServer (Microsoft) / footprints 440-450 of 714")
	)
	(layers
		(0 "F.Cu" signal "TOP")
		(4 "In1.Cu" signal "02_GND")
		(6 "In2.Cu" signal "03_SIG")
		(8 "In3.Cu" signal "04_SIG")
		(10 "In4.Cu" signal "05_GND")
		(12 "In5.Cu" signal "06_PWR1")
		(14 "In6.Cu" signal "07_SIG")
		(16 "In7.Cu" signal "08_SIG")
		(18 "In8.Cu" signal "09_GND")
		(2 "B.Cu" signal "BOTTOM")
		(9 "F.Adhes" user "F.Adhesive")
		(11 "B.Adhes" user "B.Adhesive")
		(13 "F.Paste" user "Package Geometry/Pastemask Top")
		(15 "B.Paste" user "Package Geometry/Pastemask Bottom")
		(5 "F.SilkS" user "Ref Des/Silkscreen Top")
		(7 "B.SilkS" user "Ref Des/Silkscreen Bottom")
		(1 "F.Mask" user "Board Geometry/Soldermask Top")
		(3 "B.Mask" user "Board Geometry/Soldermask Bottom")
		(17 "Dwgs.User" user "User.Drawings")
		(19 "Cmts.User" user "User.Comments")
		(21 "Eco1.User" user "User.Eco1")
		(23 "Eco2.User" user "User.Eco2")
		(25 "Edge.Cuts" user "Board Geometry/Outline")
		(27 "Margin" user)
		(31 "F.CrtYd" user "Package Geometry/Place Bound Top")
		(29 "B.CrtYd" user "Package Geometry/Place Bound Bottom")
		(35 "F.Fab" user "Ref Des/Assembly Top")
		(33 "B.Fab" user "Ref Des/Assembly Bottom")
		(45 "User.4" user "COMPVAL_TYPE_BOTTOM")
	)
	(footprint ""
		(layer "B.Cu")
		(at 73.05101 1.899006)
		(property "Reference" "V_A-DQ15"
			(at 0 0 0)
			(layer "B.SilkS")
			(hide yes)
			(effects
				(font
					(size 1.27 1.27)
				)
				(justify mirror)
			)
		)
		(property "Value" ""
			(at 0 0 0)
			(layer "B.Fab")
			(effects
				(font
					(size 1.27 1.27)
				)
				(justify mirror)
			)
		)
		(duplicate_pad_numbers_are_jumpers no)
		(pad "1" thru_hole circle
			(at 0 0 180)
			(size 0.4572 0.4572)
			(drill 0.20574)
			(layers "*.Cu" "*.Mask")
			(remove_unused_layers no)
			(net "DDR0_32A_DQ15")
			(clearance 0.1143)
			(thermal_gap 0.1143)
		)
	)
	(footprint ""
		(layer "B.Cu")
		(at 37.084 44.831)
		(property "Reference" "TP12"
			(at 1.016 -1.49733 0)
			(unlocked yes)
			(layer "B.SilkS")
			(effects
				(font
					(size 0.7874 0.5842)
					(thickness 0.127)
				)
				(justify left mirror)
			)
		)
		(property "Value" "*"
			(at 0.4826 -0.14732 0)
			(unlocked yes)
			(layer "B.Fab")
			(hide yes)
			(effects
				(font
					(size 1.27 0.9652)
					(thickness 0.000001)
				)
				(justify left mirror)
			)
		)
		(property "Device Type" "TP_SMALL"
			(at 0.4826 -0.14732 0)
			(unlocked yes)
			(layer "B.Fab")
			(hide yes)
			(effects
				(font
					(size 1.27 0.9652)
					(thickness 0.000001)
				)
				(justify left mirror)
			)
		)
		(duplicate_pad_numbers_are_jumpers no)
		(fp_line
			(start -0.8636 -0.8636)
			(end 0.8636 -0.8636)
			(stroke
				(width 0.1524)
				(type default)
			)
			(layer "B.SilkS")
		)
		(fp_line
			(start -0.8636 0.8636)
			(end -0.8636 -0.8636)
			(stroke
				(width 0.1524)
				(type default)
			)
			(layer "B.SilkS")
		)
		(fp_line
			(start 0.8636 -0.8636)
			(end 0.8636 0.8636)
			(stroke
				(width 0.1524)
				(type default)
			)
			(layer "B.SilkS")
		)
		(fp_line
			(start 0.8636 0.8636)
			(end -0.8636 0.8636)
			(stroke
				(width 0.1524)
				(type default)
			)
			(layer "B.SilkS")
		)
		(fp_poly
			(pts
				(xy 0.635 -0.635) (xy 0.635 0.635) (xy -0.635 0.635) (xy -0.635 -0.635)
			)
			(stroke
				(width 0)
				(type default)
			)
			(fill no)
			(layer "B.CrtYd")
		)
		(pad "1" smd rect
			(at 0 0 180)
			(size 1.27 1.27)
			(layers "B.Cu" "B.Mask" "B.Paste")
			(net "DEBUG_CPLD_PGRM_JTAG_TDO")
		)
	)
	(footprint ""
		(layer "B.Cu")
		(at 23.749 10.414 90)
		(property "Reference" "R44"
			(at 0 0 90)
			(layer "B.SilkS")
			(hide yes)
			(effects
				(font
					(size 1.27 1.27)
				)
				(justify mirror)
			)
		)
		(property "Value" "4.75K"
			(at 0.148158 1.3462 0)
			(unlocked yes)
			(layer "B.Fab")
			(hide yes)
			(effects
				(font
					(size 1.27 0.9652)
					(thickness 0.000001)
				)
				(justify left mirror)
			)
		)
		(property "Device Type" "REST4024"
			(at 0.148158 1.3462 0)
			(unlocked yes)
			(layer "B.Fab")
			(hide yes)
			(effects
				(font
					(size 1.27 0.9652)
					(thickness 0.000001)
				)
				(justify left mirror)
			)
		)
		(duplicate_pad_numbers_are_jumpers no)
		(fp_poly
			(pts
				(xy -0.635 1.0668) (xy -0.635 -1.0668) (xy 0.635 -1.0668) (xy 0.635 1.0668)
			)
			(stroke
				(width 0)
				(type default)
			)
			(fill no)
			(layer "B.CrtYd")
		)
		(fp_line
			(start 0.254 -0.508)
			(end -0.254 -0.508)
			(stroke
				(width 0.0254)
				(type default)
			)
			(layer "B.Fab")
		)
		(fp_line
			(start -0.254 -0.508)
			(end -0.254 0.508)
			(stroke
				(width 0.0254)
				(type default)
			)
			(layer "B.Fab")
		)
		(fp_line
			(start 0.254 0.508)
			(end 0.254 -0.508)
			(stroke
				(width 0.0254)
				(type default)
			)
			(layer "B.Fab")
		)
		(fp_line
			(start -0.254 0.508)
			(end 0.254 0.508)
			(stroke
				(width 0.0254)
				(type default)
			)
			(layer "B.Fab")
		)
		(pad "1" smd rect
			(at 0 -0.4191 270)
			(size 0.508 0.5334)
			(layers "B.Cu" "B.Mask" "B.Paste")
			(net "VDD_3.3V")
		)
		(pad "2" smd rect
			(at 0 0.4191 270)
			(size 0.508 0.5334)
			(layers "B.Cu" "B.Mask" "B.Paste")
			(net "PGRM_JTAG_TDI")
		)
		(zone
			(layer "B.Cu")
			(hatch none 0.5)
			(connect_pads
				(clearance 0)
			)
			(min_thickness 0.25)
			(keepout
				(tracks not_allowed)
				(vias allowed)
				(pads allowed)
				(copperpour not_allowed)
				(footprints allowed)
			)
			(placement
				(enabled no)
				(sheetname "")
			)
			(fill
				(thermal_gap 0.5)
				(thermal_bridge_width 0.5)
				(island_removal_mode 0)
			)
			(polygon
				(pts
					(xy 23.7236 10.4394) (xy 23.7744 10.4394) (xy 23.7744 10.3886) (xy 23.7236 10.3886)
				)
			)
		)
	)
	(footprint ""
		(layer "B.Cu")
		(at 20.701 16.891 180)
		(property "Reference" "R32"
			(at 1.04267 -1.143 270)
			(unlocked yes)
			(layer "B.SilkS")
			(effects
				(font
					(size 0.7874 0.5842)
					(thickness 0.127)
				)
				(justify left mirror)
			)
		)
		(property "Value" "4.75K"
			(at 0.148158 1.3462 90)
			(unlocked yes)
			(layer "B.Fab")
			(hide yes)
			(effects
				(font
					(size 1.27 0.9652)
					(thickness 0.000001)
				)
				(justify left mirror)
			)
		)
		(property "Device Type" "REST4024"
			(at 0.148158 1.3462 90)
			(unlocked yes)
			(layer "B.Fab")
			(hide yes)
			(effects
				(font
					(size 1.27 0.9652)
					(thickness 0.000001)
				)
				(justify left mirror)
			)
		)
		(duplicate_pad_numbers_are_jumpers no)
		(fp_poly
			(pts
				(xy -0.635 1.0668) (xy -0.635 -1.0668) (xy 0.635 -1.0668) (xy 0.635 1.0668)
			)
			(stroke
				(width 0)
				(type default)
			)
			(fill no)
			(layer "B.CrtYd")
		)
		(fp_line
			(start 0.254 0.508)
			(end 0.254 -0.508)
			(stroke
				(width 0.0254)
				(type default)
			)
			(layer "B.Fab")
		)
		(fp_line
			(start 0.254 -0.508)
			(end -0.254 -0.508)
			(stroke
				(width 0.0254)
				(type default)
			)
			(layer "B.Fab")
		)
		(fp_line
			(start -0.254 0.508)
			(end 0.254 0.508)
			(stroke
				(width 0.0254)
				(type default)
			)
			(layer "B.Fab")
		)
		(fp_line
			(start -0.254 -0.508)
			(end -0.254 0.508)
			(stroke
				(width 0.0254)
				(type default)
			)
			(layer "B.Fab")
		)
		(pad "1" smd rect
			(at 0 -0.4191)
			(size 0.508 0.5334)
			(layers "B.Cu" "B.Mask" "B.Paste")
			(net "NFP_ARM_SPI_FLASH_SEL")
		)
		(pad "2" smd rect
			(at 0 0.4191)
			(size 0.508 0.5334)
			(layers "B.Cu" "B.Mask" "B.Paste")
			(net "GND")
		)
		(zone
			(layer "B.Cu")
			(hatch none 0.5)
			(connect_pads
				(clearance 0)
			)
			(min_thickness 0.25)
			(keepout
				(tracks not_allowed)
				(vias allowed)
				(pads allowed)
				(copperpour not_allowed)
				(footprints allowed)
			)
			(placement
				(enabled no)
				(sheetname "")
			)
			(fill
				(thermal_gap 0.5)
				(thermal_bridge_width 0.5)
				(island_removal_mode 0)
			)
			(polygon
				(pts
					(xy 20.7264 16.9164) (xy 20.7264 16.8656) (xy 20.6756 16.8656) (xy 20.6756 16.9164)
				)
			)
		)
	)
	(footprint ""
		(layer "B.Cu")
		(at 38.989 48.641)
		(property "Reference" "TP3"
			(at 1.49733 3.429 270)
			(unlocked yes)
			(layer "B.SilkS")
			(effects
				(font
					(size 0.7874 0.5842)
					(thickness 0.127)
				)
				(justify left mirror)
			)
		)
		(property "Value" "*"
			(at 0.4826 -0.14732 0)
			(unlocked yes)
			(layer "B.Fab")
			(hide yes)
			(effects
				(font
					(size 1.27 0.9652)
					(thickness 0.000001)
				)
				(justify left mirror)
			)
		)
		(property "Device Type" "TP_SMALL"
			(at 0.4826 -0.14732 0)
			(unlocked yes)
			(layer "B.Fab")
			(hide yes)
			(effects
				(font
					(size 1.27 0.9652)
					(thickness 0.000001)
				)
				(justify left mirror)
			)
		)
		(duplicate_pad_numbers_are_jumpers no)
		(fp_line
			(start -0.8636 -0.8636)
			(end 0.8636 -0.8636)
			(stroke
				(width 0.1524)
				(type default)
			)
			(layer "B.SilkS")
		)
		(fp_line
			(start -0.8636 0.8636)
			(end -0.8636 -0.8636)
			(stroke
				(width 0.1524)
				(type default)
			)
			(layer "B.SilkS")
		)
		(fp_line
			(start 0.8636 -0.8636)
			(end 0.8636 0.8636)
			(stroke
				(width 0.1524)
				(type default)
			)
			(layer "B.SilkS")
		)
		(fp_line
			(start 0.8636 0.8636)
			(end -0.8636 0.8636)
			(stroke
				(width 0.1524)
				(type default)
			)
			(layer "B.SilkS")
		)
		(fp_poly
			(pts
				(xy 0.635 -0.635) (xy 0.635 0.635) (xy -0.635 0.635) (xy -0.635 -0.635)
			)
			(stroke
				(width 0)
				(type default)
			)
			(fill no)
			(layer "B.CrtYd")
		)
		(pad "1" smd rect
			(at 0 0 180)
			(size 1.27 1.27)
			(layers "B.Cu" "B.Mask" "B.Paste")
			(net "CNTRL_SPI_MISO")
		)
	)
	(footprint ""
		(layer "B.Cu")
		(at 56.736996 6.042025 90)
		(property "Reference" "C39"
			(at 1.443355 -0.602996 0)
			(unlocked yes)
			(layer "B.SilkS")
			(effects
				(font
					(size 0.7874 0.5842)
					(thickness 0.127)
				)
				(justify mirror)
			)
		)
		(property "Value" ""
			(at 0 0 90)
			(layer "B.Fab")
			(effects
				(font
					(size 1.27 1.27)
				)
				(justify mirror)
			)
		)
		(duplicate_pad_numbers_are_jumpers no)
		(fp_circle
			(center 0 0)
			(end 0 0.104648)
			(stroke
				(width 0.1016)
				(type default)
			)
			(fill no)
			(layer "B.SilkS")
		)
		(fp_poly
			(pts
				(xy 0.381 -0.889) (xy 0.381 0.889) (xy -0.381 0.889) (xy -0.381 -0.889)
			)
			(stroke
				(width 0)
				(type default)
			)
			(fill no)
			(layer "B.CrtYd")
		)
		(fp_line
			(start 0.508 -1.016)
			(end 0.254 -1.016)
			(stroke
				(width 0.0254)
				(type default)
			)
			(layer "B.Fab")
		)
		(fp_line
			(start 0.254 -1.016)
			(end -0.508 -1.016)
			(stroke
				(width 0.0254)
				(type default)
			)
			(layer "B.Fab")
		)
		(fp_line
			(start -0.508 -1.016)
			(end -0.508 1.016)
			(stroke
				(width 0.0254)
				(type default)
			)
			(layer "B.Fab")
		)
		(fp_line
			(start 0.508 1.016)
			(end 0.508 -1.016)
			(stroke
				(width 0.0254)
				(type default)
			)
			(layer "B.Fab")
		)
		(fp_line
			(start -0.508 1.016)
			(end 0.508 1.016)
			(stroke
				(width 0.0254)
				(type default)
			)
			(layer "B.Fab")
		)
		(pad "1" smd custom
			(at 0 -0.500126 270)
			(size 0.127 0.127)
			(layers "B.Cu" "B.Mask" "B.Paste")
			(net "VDDAH_PCIE0")
			(options
				(clearance outline)
				(anchor circle)
			)
			(primitives
				(gr_poly
					(pts
						(xy -0.1778 0.254) (xy 0.1778 0.254) (xy 0.254 0.1778) (xy 0.254 -0.1778) (xy 0.1778 -0.254) (xy -0.1778 -0.254)
						(xy -0.254 -0.1778) (xy -0.254 0.1778)
					)
					(width 0)
					(fill yes)
				)
			)
		)
		(pad "2" smd custom
			(at 0 0.500126 270)
			(size 0.127 0.127)
			(layers "B.Cu" "B.Mask" "B.Paste")
			(net "GND")
			(options
				(clearance outline)
				(anchor circle)
			)
			(primitives
				(gr_poly
					(pts
						(xy -0.1778 0.254) (xy 0.1778 0.254) (xy 0.254 0.1778) (xy 0.254 -0.1778) (xy 0.1778 -0.254) (xy -0.1778 -0.254)
						(xy -0.254 -0.1778) (xy -0.254 0.1778)
					)
					(width 0)
					(fill yes)
				)
			)
		)
	)
	(footprint ""
		(layer "B.Cu")
		(at 23.495 13.589)
		(property "Reference" "R31"
			(at 0.86233 1.016 270)
			(unlocked yes)
			(layer "B.SilkS")
			(effects
				(font
					(size 0.7874 0.5842)
					(thickness 0.127)
				)
				(justify left mirror)
			)
		)
		(property "Value" "4.75K"
			(at 0.148158 1.3462 270)
			(unlocked yes)
			(layer "B.Fab")
			(hide yes)
			(effects
				(font
					(size 1.27 0.9652)
					(thickness 0.000001)
				)
				(justify left mirror)
			)
		)
		(property "Device Type" "REST4024"
			(at 0.148158 1.3462 270)
			(unlocked yes)
			(layer "B.Fab")
			(hide yes)
			(effects
				(font
					(size 1.27 0.9652)
					(thickness 0.000001)
				)
				(justify left mirror)
			)
		)
		(duplicate_pad_numbers_are_jumpers no)
		(fp_poly
			(pts
				(xy -0.635 1.0668) (xy -0.635 -1.0668) (xy 0.635 -1.0668) (xy 0.635 1.0668)
			)
			(stroke
				(width 0)
				(type default)
			)
			(fill no)
			(layer "B.CrtYd")
		)
		(fp_line
			(start -0.254 -0.508)
			(end -0.254 0.508)
			(stroke
				(width 0.0254)
				(type default)
			)
			(layer "B.Fab")
		)
		(fp_line
			(start -0.254 0.508)
			(end 0.254 0.508)
			(stroke
				(width 0.0254)
				(type default)
			)
			(layer "B.Fab")
		)
		(fp_line
			(start 0.254 -0.508)
			(end -0.254 -0.508)
			(stroke
				(width 0.0254)
				(type default)
			)
			(layer "B.Fab")
		)
		(fp_line
			(start 0.254 0.508)
			(end 0.254 -0.508)
			(stroke
				(width 0.0254)
				(type default)
			)
			(layer "B.Fab")
		)
		(pad "1" smd rect
			(at 0 -0.4191 180)
			(size 0.508 0.5334)
			(layers "B.Cu" "B.Mask" "B.Paste")
			(net "VDD_3.3V")
		)
		(pad "2" smd rect
			(at 0 0.4191 180)
			(size 0.508 0.5334)
			(layers "B.Cu" "B.Mask" "B.Paste")
			(net "NFP_CFG_SPI_FLASH_WP_L")
		)
		(zone
			(layer "B.Cu")
			(hatch none 0.5)
			(connect_pads
				(clearance 0)
			)
			(min_thickness 0.25)
			(keepout
				(tracks not_allowed)
				(vias allowed)
				(pads allowed)
				(copperpour not_allowed)
				(footprints allowed)
			)
			(placement
				(enabled no)
				(sheetname "")
			)
			(fill
				(thermal_gap 0.5)
				(thermal_bridge_width 0.5)
				(island_removal_mode 0)
			)
			(polygon
				(pts
					(xy 23.4696 13.5636) (xy 23.4696 13.6144) (xy 23.5204 13.6144) (xy 23.5204 13.5636)
				)
			)
		)
	)
	(footprint ""
		(layer "B.Cu")
		(at 66.236977 17.542002 180)
		(property "Reference" "C190"
			(at -0.919353 0.143002 270)
			(unlocked yes)
			(layer "B.SilkS")
			(effects
				(font
					(size 0.7874 0.5842)
					(thickness 0.127)
				)
				(justify mirror)
			)
		)
		(property "Value" ""
			(at 0 0 0)
			(layer "B.Fab")
			(effects
				(font
					(size 1.27 1.27)
				)
				(justify mirror)
			)
		)
		(duplicate_pad_numbers_are_jumpers no)
		(fp_circle
			(center 0 0)
			(end -0.104648 0)
			(stroke
				(width 0.1016)
				(type default)
			)
			(fill no)
			(layer "B.SilkS")
		)
		(fp_poly
			(pts
				(xy 0.381 -0.889) (xy 0.381 0.889) (xy -0.381 0.889) (xy -0.381 -0.889)
			)
			(stroke
				(width 0)
				(type default)
			)
			(fill no)
			(layer "B.CrtYd")
		)
		(fp_line
			(start 0.508 1.016)
			(end 0.508 -1.016)
			(stroke
				(width 0.0254)
				(type default)
			)
			(layer "B.Fab")
		)
		(fp_line
			(start 0.508 -1.016)
			(end 0.254 -1.016)
			(stroke
				(width 0.0254)
				(type default)
			)
			(layer "B.Fab")
		)
		(fp_line
			(start 0.254 -1.016)
			(end -0.508 -1.016)
			(stroke
				(width 0.0254)
				(type default)
			)
			(layer "B.Fab")
		)
		(fp_line
			(start -0.508 1.016)
			(end 0.508 1.016)
			(stroke
				(width 0.0254)
				(type default)
			)
			(layer "B.Fab")
		)
		(fp_line
			(start -0.508 -1.016)
			(end -0.508 1.016)
			(stroke
				(width 0.0254)
				(type default)
			)
			(layer "B.Fab")
		)
		(pad "1" smd custom
			(at 0 -0.500126)
			(size 0.127 0.127)
			(layers "B.Cu" "B.Mask" "B.Paste")
			(net "DDR_VDDQ")
			(options
				(clearance outline)
				(anchor circle)
			)
			(primitives
				(gr_poly
					(pts
						(xy -0.1778 0.254) (xy 0.1778 0.254) (xy 0.254 0.1778) (xy 0.254 -0.1778) (xy 0.1778 -0.254) (xy -0.1778 -0.254)
						(xy -0.254 -0.1778) (xy -0.254 0.1778)
					)
					(width 0)
					(fill yes)
				)
			)
		)
		(pad "2" smd custom
			(at 0 0.500126)
			(size 0.127 0.127)
			(layers "B.Cu" "B.Mask" "B.Paste")
			(net "GND")
			(options
				(clearance outline)
				(anchor circle)
			)
			(primitives
				(gr_poly
					(pts
						(xy -0.1778 0.254) (xy 0.1778 0.254) (xy 0.254 0.1778) (xy 0.254 -0.1778) (xy 0.1778 -0.254) (xy -0.1778 -0.254)
						(xy -0.254 -0.1778) (xy -0.254 0.1778)
					)
					(width 0)
					(fill yes)
				)
			)
		)
	)
	(footprint ""
		(layer "B.Cu")
		(at 75.451005 25.013006)
		(property "Reference" "V_A-CB0"
			(at 0 0 0)
			(layer "B.SilkS")
			(hide yes)
			(effects
				(font
					(size 1.27 1.27)
				)
				(justify mirror)
			)
		)
		(property "Value" ""
			(at 0 0 0)
			(layer "B.Fab")
			(effects
				(font
					(size 1.27 1.27)
				)
				(justify mirror)
			)
		)
		(duplicate_pad_numbers_are_jumpers no)
		(pad "1" thru_hole circle
			(at 0 0 180)
			(size 0.4572 0.4572)
			(drill 0.20574)
			(layers "*.Cu" "*.Mask")
			(remove_unused_layers no)
			(net "DDR0_32A_CB0")
			(clearance 0.1143)
			(thermal_gap 0.1143)
		)
	)
	(footprint ""
		(layer "B.Cu")
		(at 81.050994 25.013006)
		(property "Reference" "V3_A-BA0"
			(at 0 0 0)
			(layer "B.SilkS")
			(hide yes)
			(effects
				(font
					(size 1.27 1.27)
				)
				(justify mirror)
			)
		)
		(property "Value" ""
			(at 0 0 0)
			(layer "B.Fab")
			(effects
				(font
					(size 1.27 1.27)
				)
				(justify mirror)
			)
		)
		(duplicate_pad_numbers_are_jumpers no)
		(pad "1" thru_hole circle
			(at 0 0 180)
			(size 0.4572 0.4572)
			(drill 0.20574)
			(layers "*.Cu" "*.Mask")
			(remove_unused_layers no)
			(net "DDR0_32A_BA0")
			(clearance 0.1143)
			(thermal_gap 0.1143)
		)
	)
	(footprint ""
		(layer "B.Cu")
		(at 26.289 8.509 90)
		(property "Reference" "R404"
			(at 0.73533 2.286 0)
			(unlocked yes)
			(layer "B.SilkS")
			(effects
				(font
					(size 0.7874 0.5842)
					(thickness 0.127)
				)
				(justify left mirror)
			)
		)
		(property "Value" "4.75K"
			(at 0.148158 1.3462 0)
			(unlocked yes)
			(layer "B.Fab")
			(hide yes)
			(effects
				(font
					(size 1.27 0.9652)
					(thickness 0.000001)
				)
				(justify left mirror)
			)
		)
		(property "Device Type" "REST4024"
			(at 0.148158 1.3462 0)
			(unlocked yes)
			(layer "B.Fab")
			(hide yes)
			(effects
				(font
					(size 1.27 0.9652)
					(thickness 0.000001)
				)
				(justify left mirror)
			)
		)
		(duplicate_pad_numbers_are_jumpers no)
		(fp_poly
			(pts
				(xy -0.635 1.0668) (xy -0.635 -1.0668) (xy 0.635 -1.0668) (xy 0.635 1.0668)
			)
			(stroke
				(width 0)
				(type default)
			)
			(fill no)
			(layer "B.CrtYd")
		)
		(fp_line
			(start 0.254 -0.508)
			(end -0.254 -0.508)
			(stroke
				(width 0.0254)
				(type default)
			)
			(layer "B.Fab")
		)
		(fp_line
			(start -0.254 -0.508)
			(end -0.254 0.508)
			(stroke
				(width 0.0254)
				(type default)
			)
			(layer "B.Fab")
		)
		(fp_line
			(start 0.254 0.508)
			(end 0.254 -0.508)
			(stroke
				(width 0.0254)
				(type default)
			)
			(layer "B.Fab")
		)
		(fp_line
			(start -0.254 0.508)
			(end 0.254 0.508)
			(stroke
				(width 0.0254)
				(type default)
			)
			(layer "B.Fab")
		)
		(pad "1" smd rect
			(at 0 -0.4191 270)
			(size 0.508 0.5334)
			(layers "B.Cu" "B.Mask" "B.Paste")
			(net "VDD_3.3V")
		)
		(pad "2" smd rect
			(at 0 0.4191 270)
			(size 0.508 0.5334)
			(layers "B.Cu" "B.Mask" "B.Paste")
			(net "NFP_JTAG_ARM_TDO")
		)
		(zone
			(layer "B.Cu")
			(hatch none 0.5)
			(connect_pads
				(clearance 0)
			)
			(min_thickness 0.25)
			(keepout
				(tracks not_allowed)
				(vias allowed)
				(pads allowed)
				(copperpour not_allowed)
				(footprints allowed)
			)
			(placement
				(enabled no)
				(sheetname "")
			)
			(fill
				(thermal_gap 0.5)
				(thermal_bridge_width 0.5)
				(island_removal_mode 0)
			)
			(polygon
				(pts
					(xy 26.2636 8.5344) (xy 26.3144 8.5344) (xy 26.3144 8.4836) (xy 26.2636 8.4836)
				)
			)
		)
	)
)
